(kicad_pcb
	(version 20260206)
	(generator "pcbnew")
	(generator_version "10.0")
	(general
		(thickness 1.6)
		(legacy_teardrops no)
	)
	(paper "A4")
	(title_block
		(title "04192023_DAF0TMB3IC0_F0TG_MB_C_brd_V02_OCP.brd")
		(comment 1 "Grand Teton / footprints 2463-2470 of 8354")
	)
	(layers
		(0 "F.Cu" signal "TOP")
		(4 "In1.Cu" signal "GND")
		(6 "In2.Cu" signal "IN1")
		(8 "In3.Cu" signal "GND1")
		(10 "In4.Cu" signal "IN2")
		(12 "In5.Cu" signal "GND2")
		(14 "In6.Cu" signal "IN3")
		(16 "In7.Cu" signal "GND3")
		(18 "In8.Cu" signal "VCC")
		(20 "In9.Cu" signal "VCC1")
		(22 "In10.Cu" signal "GND4")
		(24 "In11.Cu" signal "IN4")
		(26 "In12.Cu" signal "GND5")
		(28 "In13.Cu" signal "IN5")
		(30 "In14.Cu" signal "GND6")
		(32 "In15.Cu" signal "IN6")
		(34 "In16.Cu" signal "GND7")
		(2 "B.Cu" signal "BOTTOM")
		(9 "F.Adhes" user "F.Adhesive")
		(11 "B.Adhes" user "B.Adhesive")
		(13 "F.Paste" user "Package Geometry/Pastemask Top")
		(15 "B.Paste" user "Package Geometry/Pastemask Bottom")
		(5 "F.SilkS" user "Ref Des/Silkscreen Top")
		(7 "B.SilkS" user "Ref Des/Silkscreen Bottom")
		(1 "F.Mask" user "Board Geometry/Soldermask Top")
		(3 "B.Mask" user "Board Geometry/Soldermask Bottom")
		(17 "Dwgs.User" user "User.Drawings")
		(19 "Cmts.User" user "User.Comments")
		(21 "Eco1.User" user "User.Eco1")
		(23 "Eco2.User" user "User.Eco2")
		(25 "Edge.Cuts" user "Board Geometry/Outline")
		(27 "Margin" user)
		(31 "F.CrtYd" user "Package Geometry/Place Bound Top")
		(29 "B.CrtYd" user "Package Geometry/Place Bound Bottom")
		(35 "F.Fab" user "Ref Des/Assembly Top")
		(33 "B.Fab" user "Ref Des/Assembly Bottom")
	)
	(footprint ""
		(layer "F.Cu")
		(at 116.045234 -77.002894 90)
		(property "Reference" "PC6015"
			(at 0 0 90)
			(layer "F.SilkS")
			(hide yes)
			(effects
				(font
					(size 1.27 1.27)
				)
			)
		)
		(property "Value" ""
			(at 0 0 90)
			(layer "F.Fab")
			(effects
				(font
					(size 1.27 1.27)
				)
			)
		)
		(duplicate_pad_numbers_are_jumpers no)
		(fp_line
			(start 1.524 -0.762)
			(end 1.524 0.762)
			(stroke
				(width 0.1524)
				(type default)
			)
			(layer "F.SilkS")
		)
		(fp_line
			(start -1.524 -0.762)
			(end 1.524 -0.762)
			(stroke
				(width 0.1524)
				(type default)
			)
			(layer "F.SilkS")
		)
		(fp_line
			(start 1.524 0.762)
			(end -1.524 0.762)
			(stroke
				(width 0.1524)
				(type default)
			)
			(layer "F.SilkS")
		)
		(fp_line
			(start -1.524 0.762)
			(end -1.524 -0.762)
			(stroke
				(width 0.1524)
				(type default)
			)
			(layer "F.SilkS")
		)
		(fp_line
			(start 1.1049 -0.724916)
			(end -1.1049 -0.724916)
			(stroke
				(width 0.1)
				(type default)
			)
			(layer "F.Fab")
		)
		(fp_line
			(start -1.1049 -0.724916)
			(end -1.1049 0.724916)
			(stroke
				(width 0.1)
				(type default)
			)
			(layer "F.Fab")
		)
		(fp_line
			(start 1.1049 0.724916)
			(end 1.1049 -0.724916)
			(stroke
				(width 0.1)
				(type default)
			)
			(layer "F.Fab")
		)
		(fp_line
			(start -1.1049 0.724916)
			(end 1.1049 0.724916)
			(stroke
				(width 0.1)
				(type default)
			)
			(layer "F.Fab")
		)
		(pad "1" smd rect
			(at -0.889 0 270)
			(size 1.016 1.27)
			(layers "F.Cu" "F.Mask" "F.Paste")
			(net "SW_P12V_AUX_P1V2_AUX_FLT")
		)
		(pad "2" smd rect
			(at 0.889 0 270)
			(size 1.016 1.27)
			(layers "F.Cu" "F.Mask" "F.Paste")
			(net "GND")
		)
	)
	(footprint ""
		(layer "F.Cu")
		(at 99.650296 -425.82973 -90)
		(property "Reference" "R4194"
			(at 0 0 270)
			(layer "F.SilkS")
			(hide yes)
			(effects
				(font
					(size 1.27 1.27)
				)
			)
		)
		(property "Value" ""
			(at 0 0 270)
			(layer "F.Fab")
			(effects
				(font
					(size 1.27 1.27)
				)
			)
		)
		(duplicate_pad_numbers_are_jumpers no)
		(fp_line
			(start -0.7874 0.4064)
			(end -0.7874 -0.4064)
			(stroke
				(width 0.1524)
				(type default)
			)
			(layer "F.SilkS")
		)
		(fp_line
			(start 0.7874 0.4064)
			(end -0.7874 0.4064)
			(stroke
				(width 0.1524)
				(type default)
			)
			(layer "F.SilkS")
		)
		(fp_line
			(start -0.7874 -0.4064)
			(end 0.7874 -0.4064)
			(stroke
				(width 0.1524)
				(type default)
			)
			(layer "F.SilkS")
		)
		(fp_line
			(start 0.7874 -0.4064)
			(end 0.7874 0.4064)
			(stroke
				(width 0.1524)
				(type default)
			)
			(layer "F.SilkS")
		)
		(fp_line
			(start -0.67945 0.3048)
			(end -0.67945 -0.305054)
			(stroke
				(width 0.1)
				(type default)
			)
			(layer "F.Fab")
		)
		(fp_line
			(start -0.12065 0.3048)
			(end -0.67945 0.3048)
			(stroke
				(width 0.1)
				(type default)
			)
			(layer "F.Fab")
		)
		(fp_line
			(start 0.120396 0.3048)
			(end 0.120396 0.2794)
			(stroke
				(width 0.1)
				(type default)
			)
			(layer "F.Fab")
		)
		(fp_line
			(start 0.67945 0.3048)
			(end 0.120396 0.3048)
			(stroke
				(width 0.1)
				(type default)
			)
			(layer "F.Fab")
		)
		(fp_line
			(start -0.12065 0.2794)
			(end -0.12065 0.3048)
			(stroke
				(width 0.1)
				(type default)
			)
			(layer "F.Fab")
		)
		(fp_line
			(start 0.120396 0.2794)
			(end -0.12065 0.2794)
			(stroke
				(width 0.1)
				(type default)
			)
			(layer "F.Fab")
		)
		(fp_line
			(start -0.12065 -0.2794)
			(end 0.12065 -0.2794)
			(stroke
				(width 0.1)
				(type default)
			)
			(layer "F.Fab")
		)
		(fp_line
			(start 0.12065 -0.2794)
			(end 0.12065 -0.3048)
			(stroke
				(width 0.1)
				(type default)
			)
			(layer "F.Fab")
		)
		(fp_line
			(start 0.12065 -0.3048)
			(end 0.67945 -0.3048)
			(stroke
				(width 0.1)
				(type default)
			)
			(layer "F.Fab")
		)
		(fp_line
			(start 0.67945 -0.3048)
			(end 0.67945 0.3048)
			(stroke
				(width 0.1)
				(type default)
			)
			(layer "F.Fab")
		)
		(fp_line
			(start -0.67945 -0.305054)
			(end -0.12065 -0.305054)
			(stroke
				(width 0.1)
				(type default)
			)
			(layer "F.Fab")
		)
		(fp_line
			(start -0.12065 -0.305054)
			(end -0.12065 -0.2794)
			(stroke
				(width 0.1)
				(type default)
			)
			(layer "F.Fab")
		)
		(pad "1" smd circle
			(at -0.40005 0 270)
			(size 0 0)
			(layers "F.Cu" "F.Mask" "F.Paste")
			(net "P3V3_AUX")
		)
		(pad "2" smd circle
			(at 0.40005 0 270)
			(size 0 0)
			(layers "F.Cu" "F.Mask" "F.Paste")
			(net "U272_2_ADD1")
		)
	)
	(footprint ""
		(layer "F.Cu")
		(at 371.195092 -383.88163 -90)
		(property "Reference" "C893"
			(at 0 0 270)
			(layer "F.SilkS")
			(hide yes)
			(effects
				(font
					(size 1.27 1.27)
				)
			)
		)
		(property "Value" ""
			(at 0 0 270)
			(layer "F.Fab")
			(effects
				(font
					(size 1.27 1.27)
				)
			)
		)
		(duplicate_pad_numbers_are_jumpers no)
		(fp_line
			(start -0.299974 0.150114)
			(end -0.299974 -0.150114)
			(stroke
				(width 0.1)
				(type default)
			)
			(layer "F.Fab")
		)
		(fp_line
			(start 0.299974 0.150114)
			(end -0.299974 0.150114)
			(stroke
				(width 0.1)
				(type default)
			)
			(layer "F.Fab")
		)
		(fp_line
			(start -0.299974 -0.150114)
			(end 0.299974 -0.150114)
			(stroke
				(width 0.1)
				(type default)
			)
			(layer "F.Fab")
		)
		(fp_line
			(start 0.299974 -0.150114)
			(end 0.299974 0.150114)
			(stroke
				(width 0.1)
				(type default)
			)
			(layer "F.Fab")
		)
		(pad "1" smd rect
			(at -0.2667 0 270)
			(size 0.3048 0.381)
			(layers "F.Cu" "F.Mask" "F.Paste")
			(net "P5E_CPU0_P3_TX_C_DP<4>")
		)
		(pad "2" smd rect
			(at 0.2667 0 270)
			(size 0.3048 0.381)
			(layers "F.Cu" "F.Mask" "F.Paste")
			(net "P5E_CPU0_P3_TX_DP<4>")
		)
	)
	(footprint ""
		(layer "F.Cu")
		(at 90.832178 -139.80541)
		(property "Reference" "C5003"
			(at 0 0 0)
			(layer "F.SilkS")
			(hide yes)
			(effects
				(font
					(size 1.27 1.27)
				)
			)
		)
		(property "Value" ""
			(at 0 0 0)
			(layer "F.Fab")
			(effects
				(font
					(size 1.27 1.27)
				)
			)
		)
		(duplicate_pad_numbers_are_jumpers no)
		(fp_line
			(start -0.7874 -0.4064)
			(end 0.7874 -0.4064)
			(stroke
				(width 0.1524)
				(type default)
			)
			(layer "F.SilkS")
		)
		(fp_line
			(start -0.7874 0.4064)
			(end -0.7874 -0.4064)
			(stroke
				(width 0.1524)
				(type default)
			)
			(layer "F.SilkS")
		)
		(fp_line
			(start 0.7874 -0.4064)
			(end 0.7874 0.4064)
			(stroke
				(width 0.1524)
				(type default)
			)
			(layer "F.SilkS")
		)
		(fp_line
			(start 0.7874 0.4064)
			(end -0.7874 0.4064)
			(stroke
				(width 0.1524)
				(type default)
			)
			(layer "F.SilkS")
		)
		(fp_line
			(start -0.67945 -0.305054)
			(end -0.12065 -0.305054)
			(stroke
				(width 0.1)
				(type default)
			)
			(layer "F.Fab")
		)
		(fp_line
			(start -0.67945 0.3048)
			(end -0.67945 -0.305054)
			(stroke
				(width 0.1)
				(type default)
			)
			(layer "F.Fab")
		)
		(fp_line
			(start -0.12065 -0.305054)
			(end -0.12065 -0.2794)
			(stroke
				(width 0.1)
				(type default)
			)
			(layer "F.Fab")
		)
		(fp_line
			(start -0.12065 -0.2794)
			(end 0.12065 -0.2794)
			(stroke
				(width 0.1)
				(type default)
			)
			(layer "F.Fab")
		)
		(fp_line
			(start -0.12065 0.2794)
			(end -0.12065 0.3048)
			(stroke
				(width 0.1)
				(type default)
			)
			(layer "F.Fab")
		)
		(fp_line
			(start -0.12065 0.3048)
			(end -0.67945 0.3048)
			(stroke
				(width 0.1)
				(type default)
			)
			(layer "F.Fab")
		)
		(fp_line
			(start 0.120396 0.2794)
			(end -0.12065 0.2794)
			(stroke
				(width 0.1)
				(type default)
			)
			(layer "F.Fab")
		)
		(fp_line
			(start 0.120396 0.3048)
			(end 0.120396 0.2794)
			(stroke
				(width 0.1)
				(type default)
			)
			(layer "F.Fab")
		)
		(fp_line
			(start 0.12065 -0.3048)
			(end 0.67945 -0.3048)
			(stroke
				(width 0.1)
				(type default)
			)
			(layer "F.Fab")
		)
		(fp_line
			(start 0.12065 -0.2794)
			(end 0.12065 -0.3048)
			(stroke
				(width 0.1)
				(type default)
			)
			(layer "F.Fab")
		)
		(fp_line
			(start 0.67945 -0.3048)
			(end 0.67945 0.3048)
			(stroke
				(width 0.1)
				(type default)
			)
			(layer "F.Fab")
		)
		(fp_line
			(start 0.67945 0.3048)
			(end 0.120396 0.3048)
			(stroke
				(width 0.1)
				(type default)
			)
			(layer "F.Fab")
		)
		(pad "1" smd circle
			(at -0.40005 0)
			(size 0 0)
			(layers "F.Cu" "F.Mask" "F.Paste")
			(net "GND")
		)
		(pad "2" smd circle
			(at 0.40005 0)
			(size 0 0)
			(layers "F.Cu" "F.Mask" "F.Paste")
			(net "PWRGD_PVDDCR_CPU0_P1")
		)
	)
	(footprint ""
		(layer "F.Cu")
		(at 187.892182 -28.258008 180)
		(property "Reference" "PC2233"
			(at 0 0 180)
			(layer "F.SilkS")
			(hide yes)
			(effects
				(font
					(size 1.27 1.27)
				)
			)
		)
		(property "Value" ""
			(at 0 0 180)
			(layer "F.Fab")
			(effects
				(font
					(size 1.27 1.27)
				)
			)
		)
		(duplicate_pad_numbers_are_jumpers no)
		(fp_line
			(start 0.7874 0.4064)
			(end -0.7874 0.4064)
			(stroke
				(width 0.1524)
				(type default)
			)
			(layer "F.SilkS")
		)
		(fp_line
			(start 0.7874 -0.4064)
			(end 0.7874 0.4064)
			(stroke
				(width 0.1524)
				(type default)
			)
			(layer "F.SilkS")
		)
		(fp_line
			(start -0.7874 0.4064)
			(end -0.7874 -0.4064)
			(stroke
				(width 0.1524)
				(type default)
			)
			(layer "F.SilkS")
		)
		(fp_line
			(start -0.7874 -0.4064)
			(end 0.7874 -0.4064)
			(stroke
				(width 0.1524)
				(type default)
			)
			(layer "F.SilkS")
		)
		(fp_line
			(start 0.67945 0.3048)
			(end 0.120396 0.3048)
			(stroke
				(width 0.1)
				(type default)
			)
			(layer "F.Fab")
		)
		(fp_line
			(start 0.67945 -0.3048)
			(end 0.67945 0.3048)
			(stroke
				(width 0.1)
				(type default)
			)
			(layer "F.Fab")
		)
		(fp_line
			(start 0.12065 -0.2794)
			(end 0.12065 -0.3048)
			(stroke
				(width 0.1)
				(type default)
			)
			(layer "F.Fab")
		)
		(fp_line
			(start 0.12065 -0.3048)
			(end 0.67945 -0.3048)
			(stroke
				(width 0.1)
				(type default)
			)
			(layer "F.Fab")
		)
		(fp_line
			(start 0.120396 0.3048)
			(end 0.120396 0.2794)
			(stroke
				(width 0.1)
				(type default)
			)
			(layer "F.Fab")
		)
		(fp_line
			(start 0.120396 0.2794)
			(end -0.12065 0.2794)
			(stroke
				(width 0.1)
				(type default)
			)
			(layer "F.Fab")
		)
		(fp_line
			(start -0.12065 0.3048)
			(end -0.67945 0.3048)
			(stroke
				(width 0.1)
				(type default)
			)
			(layer "F.Fab")
		)
		(fp_line
			(start -0.12065 0.2794)
			(end -0.12065 0.3048)
			(stroke
				(width 0.1)
				(type default)
			)
			(layer "F.Fab")
		)
		(fp_line
			(start -0.12065 -0.2794)
			(end 0.12065 -0.2794)
			(stroke
				(width 0.1)
				(type default)
			)
			(layer "F.Fab")
		)
		(fp_line
			(start -0.12065 -0.305054)
			(end -0.12065 -0.2794)
			(stroke
				(width 0.1)
				(type default)
			)
			(layer "F.Fab")
		)
		(fp_line
			(start -0.67945 0.3048)
			(end -0.67945 -0.305054)
			(stroke
				(width 0.1)
				(type default)
			)
			(layer "F.Fab")
		)
		(fp_line
			(start -0.67945 -0.305054)
			(end -0.12065 -0.305054)
			(stroke
				(width 0.1)
				(type default)
			)
			(layer "F.Fab")
		)
		(pad "1" smd circle
			(at -0.40005 0 180)
			(size 0 0)
			(layers "F.Cu" "F.Mask" "F.Paste")
			(net "P12V_SCM_VCC")
		)
		(pad "2" smd circle
			(at 0.40005 0 180)
			(size 0 0)
			(layers "F.Cu" "F.Mask" "F.Paste")
			(net "GND")
		)
	)
	(footprint ""
		(layer "F.Cu")
		(at 412.481268 -70.74408)
		(property "Reference" "R1500"
			(at 0 0 0)
			(layer "F.SilkS")
			(hide yes)
			(effects
				(font
					(size 1.27 1.27)
				)
			)
		)
		(property "Value" ""
			(at 0 0 0)
			(layer "F.Fab")
			(effects
				(font
					(size 1.27 1.27)
				)
			)
		)
		(duplicate_pad_numbers_are_jumpers no)
		(fp_line
			(start -0.7874 -0.4064)
			(end 0.7874 -0.4064)
			(stroke
				(width 0.1524)
				(type default)
			)
			(layer "F.SilkS")
		)
		(fp_line
			(start -0.7874 0.4064)
			(end -0.7874 -0.4064)
			(stroke
				(width 0.1524)
				(type default)
			)
			(layer "F.SilkS")
		)
		(fp_line
			(start 0.7874 -0.4064)
			(end 0.7874 0.4064)
			(stroke
				(width 0.1524)
				(type default)
			)
			(layer "F.SilkS")
		)
		(fp_line
			(start 0.7874 0.4064)
			(end -0.7874 0.4064)
			(stroke
				(width 0.1524)
				(type default)
			)
			(layer "F.SilkS")
		)
		(fp_line
			(start -0.67945 -0.305054)
			(end -0.12065 -0.305054)
			(stroke
				(width 0.1)
				(type default)
			)
			(layer "F.Fab")
		)
		(fp_line
			(start -0.67945 0.3048)
			(end -0.67945 -0.305054)
			(stroke
				(width 0.1)
				(type default)
			)
			(layer "F.Fab")
		)
		(fp_line
			(start -0.12065 -0.305054)
			(end -0.12065 -0.2794)
			(stroke
				(width 0.1)
				(type default)
			)
			(layer "F.Fab")
		)
		(fp_line
			(start -0.12065 -0.2794)
			(end 0.12065 -0.2794)
			(stroke
				(width 0.1)
				(type default)
			)
			(layer "F.Fab")
		)
		(fp_line
			(start -0.12065 0.2794)
			(end -0.12065 0.3048)
			(stroke
				(width 0.1)
				(type default)
			)
			(layer "F.Fab")
		)
		(fp_line
			(start -0.12065 0.3048)
			(end -0.67945 0.3048)
			(stroke
				(width 0.1)
				(type default)
			)
			(layer "F.Fab")
		)
		(fp_line
			(start 0.120396 0.2794)
			(end -0.12065 0.2794)
			(stroke
				(width 0.1)
				(type default)
			)
			(layer "F.Fab")
		)
		(fp_line
			(start 0.120396 0.3048)
			(end 0.120396 0.2794)
			(stroke
				(width 0.1)
				(type default)
			)
			(layer "F.Fab")
		)
		(fp_line
			(start 0.12065 -0.3048)
			(end 0.67945 -0.3048)
			(stroke
				(width 0.1)
				(type default)
			)
			(layer "F.Fab")
		)
		(fp_line
			(start 0.12065 -0.2794)
			(end 0.12065 -0.3048)
			(stroke
				(width 0.1)
				(type default)
			)
			(layer "F.Fab")
		)
		(fp_line
			(start 0.67945 -0.3048)
			(end 0.67945 0.3048)
			(stroke
				(width 0.1)
				(type default)
			)
			(layer "F.Fab")
		)
		(fp_line
			(start 0.67945 0.3048)
			(end 0.120396 0.3048)
			(stroke
				(width 0.1)
				(type default)
			)
			(layer "F.Fab")
		)
		(pad "1" smd circle
			(at -0.40005 0)
			(size 0 0)
			(layers "F.Cu" "F.Mask" "F.Paste")
			(net "HP_LVC3_OCP_V3_1_R_EN")
		)
		(pad "2" smd circle
			(at 0.40005 0)
			(size 0 0)
			(layers "F.Cu" "F.Mask" "F.Paste")
			(net "P12V_OCP_SFF_BUF_EN_R")
		)
	)
	(footprint ""
		(layer "F.Cu")
		(at 169.368724 -379.471428)
		(property "Reference" "C743"
			(at 0 0 0)
			(layer "F.SilkS")
			(hide yes)
			(effects
				(font
					(size 1.27 1.27)
				)
			)
		)
		(property "Value" ""
			(at 0 0 0)
			(layer "F.Fab")
			(effects
				(font
					(size 1.27 1.27)
				)
			)
		)
		(duplicate_pad_numbers_are_jumpers no)
		(fp_line
			(start -0.299974 -0.150114)
			(end 0.299974 -0.150114)
			(stroke
				(width 0.1)
				(type default)
			)
			(layer "F.Fab")
		)
		(fp_line
			(start -0.299974 0.150114)
			(end -0.299974 -0.150114)
			(stroke
				(width 0.1)
				(type default)
			)
			(layer "F.Fab")
		)
		(fp_line
			(start 0.299974 -0.150114)
			(end 0.299974 0.150114)
			(stroke
				(width 0.1)
				(type default)
			)
			(layer "F.Fab")
		)
		(fp_line
			(start 0.299974 0.150114)
			(end -0.299974 0.150114)
			(stroke
				(width 0.1)
				(type default)
			)
			(layer "F.Fab")
		)
		(pad "1" smd rect
			(at -0.2667 0)
			(size 0.3048 0.381)
			(layers "F.Cu" "F.Mask" "F.Paste")
			(net "P5E_CPU1_P2_TX_C_DP<15>")
		)
		(pad "2" smd rect
			(at 0.2667 0)
			(size 0.3048 0.381)
			(layers "F.Cu" "F.Mask" "F.Paste")
			(net "P5E_CPU1_P2_TX_DP<15>")
		)
	)
	(footprint ""
		(layer "F.Cu")
		(at 105.92816 -395.55674 180)
		(property "Reference" "R670"
			(at 0 0 180)
			(layer "F.SilkS")
			(hide yes)
			(effects
				(font
					(size 1.27 1.27)
				)
			)
		)
		(property "Value" ""
			(at 0 0 180)
			(layer "F.Fab")
			(effects
				(font
					(size 1.27 1.27)
				)
			)
		)
		(duplicate_pad_numbers_are_jumpers no)
		(fp_line
			(start 0.32512 0.175006)
			(end -0.32512 0.175006)
			(stroke
				(width 0.1)
				(type default)
			)
			(layer "F.Fab")
		)
		(fp_line
			(start 0.32512 -0.175006)
			(end 0.32512 0.175006)
			(stroke
				(width 0.1)
				(type default)
			)
			(layer "F.Fab")
		)
		(fp_line
			(start -0.32512 0.175006)
			(end -0.32512 -0.175006)
			(stroke
				(width 0.1)
				(type default)
			)
			(layer "F.Fab")
		)
		(fp_line
			(start -0.32512 -0.175006)
			(end 0.32512 -0.175006)
			(stroke
				(width 0.1)
				(type default)
			)
			(layer "F.Fab")
		)
		(pad "1" smd rect
			(at -0.2667 0 180)
			(size 0.3048 0.381)
			(layers "F.Cu" "F.Mask" "F.Paste")
			(net "SMB_RT_CPU1_P1_ROM_MUX_1D_SCL")
		)
		(pad "2" smd rect
			(at 0.2667 0)
			(size 0.3048 0.381)
			(layers "F.Cu" "F.Mask" "F.Paste")
			(net "SMB_RT_CPU1_P1_ROM_MUX_1D_R_SCL")
		)
	)
)
